(kicad_pcb
	(version 20260206)
	(generator "pcbnew")
	(generator_version "10.0")
	(general
		(thickness 1.6)
		(legacy_teardrops no)
	)
	(paper "A4")
	(title_block
		(title "peb — Lightning_PEB_BRD.brd")
		(comment 1 "Lightning (Wiwynn / Facebook NVMe JBOF) / footprints 2153-2160 of 2563")
	)
	(layers
		(0 "F.Cu" signal "TOP")
		(4 "In1.Cu" signal "L2GND")
		(6 "In2.Cu" signal "L3")
		(8 "In3.Cu" signal "L4VCC")
		(10 "In4.Cu" signal "L5VCC")
		(12 "In5.Cu" signal "L6")
		(14 "In6.Cu" signal "L7GND")
		(2 "B.Cu" signal "BOTTOM")
		(9 "F.Adhes" user "F.Adhesive")
		(11 "B.Adhes" user "B.Adhesive")
		(13 "F.Paste" user "Package Geometry/Pastemask Top")
		(15 "B.Paste" user "Package Geometry/Pastemask Bottom")
		(5 "F.SilkS" user "Ref Des/Silkscreen Top")
		(7 "B.SilkS" user "Ref Des/Silkscreen Bottom")
		(1 "F.Mask" user "Board Geometry/Soldermask Top")
		(3 "B.Mask" user "Board Geometry/Soldermask Bottom")
		(17 "Dwgs.User" user "User.Drawings")
		(19 "Cmts.User" user "User.Comments")
		(21 "Eco1.User" user "User.Eco1")
		(23 "Eco2.User" user "User.Eco2")
		(25 "Edge.Cuts" user "Board Geometry/Outline")
		(27 "Margin" user)
		(31 "F.CrtYd" user "Package Geometry/Place Bound Top")
		(29 "B.CrtYd" user "Package Geometry/Place Bound Bottom")
		(35 "F.Fab" user "Ref Des/Assembly Top")
		(33 "B.Fab" user "Ref Des/Assembly Bottom")
	)
	(footprint ""
		(layer "B.Cu")
		(at 17.1196 -69.1134 180)
		(property "Reference" "R374"
			(at 0 0 0)
			(layer "B.SilkS")
			(hide yes)
			(effects
				(font
					(size 1.27 1.27)
				)
				(justify mirror)
			)
		)
		(property "Value" "0R3J-0-U-GP"
			(at 0.0254 -2.5146 180)
			(unlocked yes)
			(layer "B.Fab")
			(hide yes)
			(effects
				(font
					(size 1.016 1.016)
					(thickness 0.1524)
				)
				(justify mirror)
			)
		)
		(property "Device Type" "R603H22"
			(at 0.0254 -4.0386 180)
			(unlocked yes)
			(layer "B.Fab")
			(hide yes)
			(effects
				(font
					(size 1.016 1.016)
					(thickness 0.1524)
				)
				(justify mirror)
			)
		)
		(duplicate_pad_numbers_are_jumpers no)
		(fp_line
			(start 0.4826 0)
			(end 0.2032 0)
			(stroke
				(width 0.2032)
				(type default)
			)
			(layer "B.SilkS")
		)
		(fp_line
			(start -0.2032 0)
			(end -0.4826 0)
			(stroke
				(width 0.2032)
				(type default)
			)
			(layer "B.SilkS")
		)
		(fp_rect
			(start 0.5842 1.3335)
			(end -0.5842 -1.3335)
			(stroke
				(width 0)
				(type default)
			)
			(fill no)
			(layer "B.CrtYd")
		)
		(fp_rect
			(start 0.5842 1.3335)
			(end -0.5842 -1.3335)
			(stroke
				(width 0)
				(type default)
			)
			(fill no)
			(layer "B.Fab")
		)
		(pad "1" smd custom
			(at 0 -0.762)
			(size 0.2159 0.2159)
			(layers "B.Cu" "B.Mask" "B.Paste")
			(net "P1V5_I210")
			(options
				(clearance outline)
				(anchor circle)
			)
			(primitives
				(gr_poly
					(pts
						(arc
							(start -0.3302 0.4318)
							(mid -0.402042 0.402042)
							(end -0.4318 0.3302)
						)
						(arc
							(start -0.4318 -0.3302)
							(mid -0.402042 -0.402042)
							(end -0.3302 -0.4318)
						)
						(arc
							(start 0.3302 -0.4318)
							(mid 0.402042 -0.402042)
							(end 0.4318 -0.3302)
						)
						(arc
							(start 0.4318 0.3302)
							(mid 0.402042 0.402042)
							(end 0.3302 0.4318)
						)
					)
					(width 0)
					(fill yes)
				)
			)
		)
		(pad "2" smd custom
			(at 0 0.762)
			(size 0.2159 0.2159)
			(layers "B.Cu" "B.Mask" "B.Paste")
			(net "LAN1_51")
			(options
				(clearance outline)
				(anchor circle)
			)
			(primitives
				(gr_poly
					(pts
						(arc
							(start -0.3302 0.4318)
							(mid -0.402042 0.402042)
							(end -0.4318 0.3302)
						)
						(arc
							(start -0.4318 -0.3302)
							(mid -0.402042 -0.402042)
							(end -0.3302 -0.4318)
						)
						(arc
							(start 0.3302 -0.4318)
							(mid 0.402042 -0.402042)
							(end 0.4318 -0.3302)
						)
						(arc
							(start 0.4318 0.3302)
							(mid 0.402042 0.402042)
							(end 0.3302 0.4318)
						)
					)
					(width 0)
					(fill yes)
				)
			)
		)
	)
	(footprint ""
		(layer "B.Cu")
		(at 42.926 -117.602)
		(property "Reference" "TP97"
			(at 0 0 0)
			(layer "B.SilkS")
			(hide yes)
			(effects
				(font
					(size 1.27 1.27)
				)
				(justify mirror)
			)
		)
		(property "Value" "TPAD28-2-GP"
			(at 0.0127 -1.6637 0)
			(unlocked yes)
			(layer "B.Fab")
			(hide yes)
			(effects
				(font
					(size 1.016 1.016)
					(thickness 0.1524)
				)
				(justify mirror)
			)
		)
		(property "Device Type" "TPAD28"
			(at 0.0127 -3.1877 0)
			(unlocked yes)
			(layer "B.Fab")
			(hide yes)
			(effects
				(font
					(size 1.016 1.016)
					(thickness 0.1524)
				)
				(justify mirror)
			)
		)
		(duplicate_pad_numbers_are_jumpers no)
		(fp_poly
			(pts
				(arc
					(start 0.3556 0)
					(mid -0.3556 0)
					(end 0.3556 0)
				)
			)
			(stroke
				(width 0)
				(type default)
			)
			(fill no)
			(layer "B.CrtYd")
		)
		(fp_poly
			(pts
				(arc
					(start 0.6096 0)
					(mid -0.6096 0)
					(end 0.6096 0)
				)
			)
			(stroke
				(width 0)
				(type default)
			)
			(fill no)
			(layer "B.Fab")
		)
		(pad "1" smd circle
			(at 0 0 180)
			(size 0.7112 0.7112)
			(layers "B.Cu" "B.Mask" "B.Paste")
			(net "TP_GPIOH7")
		)
	)
	(footprint ""
		(layer "B.Cu")
		(at 226.613212 -200.007474)
		(property "Reference" "R3238"
			(at 0 0 0)
			(layer "B.SilkS")
			(hide yes)
			(effects
				(font
					(size 1.27 1.27)
				)
				(justify mirror)
			)
		)
		(property "Value" "0R2J-2-GP"
			(at -0.064008 -3.993896 0)
			(unlocked yes)
			(layer "B.Fab")
			(hide yes)
			(effects
				(font
					(size 1.016 1.016)
					(thickness 0.1524)
				)
				(justify mirror)
			)
		)
		(property "Device Type" "R402H16"
			(at -0.064008 -5.517896 0)
			(unlocked yes)
			(layer "B.Fab")
			(hide yes)
			(effects
				(font
					(size 1.016 1.016)
					(thickness 0.1524)
				)
				(justify mirror)
			)
		)
		(duplicate_pad_numbers_are_jumpers no)
		(fp_line
			(start -0.508 -0.9398)
			(end 0.508 -0.9398)
			(stroke
				(width 0.1524)
				(type default)
			)
			(layer "B.SilkS")
		)
		(fp_line
			(start 0.508 -0.9398)
			(end 0.508 0.9398)
			(stroke
				(width 0.1524)
				(type default)
			)
			(layer "B.SilkS")
		)
		(fp_rect
			(start 0.508 0.9398)
			(end -0.508 -0.9398)
			(stroke
				(width 0)
				(type default)
			)
			(fill no)
			(layer "B.CrtYd")
		)
		(fp_rect
			(start 0.508 0.9398)
			(end -0.508 -0.9398)
			(stroke
				(width 0)
				(type default)
			)
			(fill no)
			(layer "B.Fab")
		)
		(pad "1" smd custom
			(at 0 -0.4445 180)
			(size 0.1397 0.1397)
			(layers "B.Cu" "B.Mask" "B.Paste")
			(net "BMC_SSD_RST#12")
			(options
				(clearance outline)
				(anchor circle)
			)
			(primitives
				(gr_poly
					(pts
						(arc
							(start -0.1778 0.2794)
							(mid -0.249642 0.249642)
							(end -0.2794 0.1778)
						)
						(arc
							(start -0.2794 -0.1778)
							(mid -0.249642 -0.249642)
							(end -0.1778 -0.2794)
						)
						(arc
							(start 0.1778 -0.2794)
							(mid 0.249642 -0.249642)
							(end 0.2794 -0.1778)
						)
						(arc
							(start 0.2794 0.1778)
							(mid 0.249642 0.249642)
							(end 0.1778 0.2794)
						)
					)
					(width 0)
					(fill yes)
				)
			)
		)
		(pad "2" smd custom
			(at 0 0.4445 180)
			(size 0.1397 0.1397)
			(layers "B.Cu" "B.Mask" "B.Paste")
			(net "BMC_SSD_RST#0_A12")
			(options
				(clearance outline)
				(anchor circle)
			)
			(primitives
				(gr_poly
					(pts
						(arc
							(start -0.1778 0.2794)
							(mid -0.249642 0.249642)
							(end -0.2794 0.1778)
						)
						(arc
							(start -0.2794 -0.1778)
							(mid -0.249642 -0.249642)
							(end -0.1778 -0.2794)
						)
						(arc
							(start 0.1778 -0.2794)
							(mid 0.249642 -0.249642)
							(end 0.2794 -0.1778)
						)
						(arc
							(start 0.2794 0.1778)
							(mid 0.249642 0.249642)
							(end 0.1778 0.2794)
						)
					)
					(width 0)
					(fill yes)
				)
			)
		)
	)
	(footprint ""
		(layer "B.Cu")
		(at 181.321202 -9.457944 -90)
		(property "Reference" "R207"
			(at 0 0 90)
			(layer "B.SilkS")
			(hide yes)
			(effects
				(font
					(size 1.27 1.27)
				)
				(justify mirror)
			)
		)
		(property "Value" "4K7R2F-GP"
			(at -0.064008 -3.993896 270)
			(unlocked yes)
			(layer "B.Fab")
			(hide yes)
			(effects
				(font
					(size 1.016 1.016)
					(thickness 0.1524)
				)
				(justify mirror)
			)
		)
		(property "Device Type" "R402H16"
			(at -0.064008 -5.517896 270)
			(unlocked yes)
			(layer "B.Fab")
			(hide yes)
			(effects
				(font
					(size 1.016 1.016)
					(thickness 0.1524)
				)
				(justify mirror)
			)
		)
		(duplicate_pad_numbers_are_jumpers no)
		(fp_line
			(start -0.508 -0.9398)
			(end 0.508 -0.9398)
			(stroke
				(width 0.1524)
				(type default)
			)
			(layer "B.SilkS")
		)
		(fp_line
			(start 0.508 -0.9398)
			(end 0.508 0.9398)
			(stroke
				(width 0.1524)
				(type default)
			)
			(layer "B.SilkS")
		)
		(fp_rect
			(start 0.508 0.9398)
			(end -0.508 -0.9398)
			(stroke
				(width 0)
				(type default)
			)
			(fill no)
			(layer "B.CrtYd")
		)
		(fp_rect
			(start 0.508 0.9398)
			(end -0.508 -0.9398)
			(stroke
				(width 0)
				(type default)
			)
			(fill no)
			(layer "B.Fab")
		)
		(pad "1" smd custom
			(at 0 -0.4445 90)
			(size 0.1397 0.1397)
			(layers "B.Cu" "B.Mask" "B.Paste")
			(net "CLK_P_3_R")
			(options
				(clearance outline)
				(anchor circle)
			)
			(primitives
				(gr_poly
					(pts
						(arc
							(start -0.1778 0.2794)
							(mid -0.249642 0.249642)
							(end -0.2794 0.1778)
						)
						(arc
							(start -0.2794 -0.1778)
							(mid -0.249642 -0.249642)
							(end -0.1778 -0.2794)
						)
						(arc
							(start 0.1778 -0.2794)
							(mid 0.249642 -0.249642)
							(end 0.2794 -0.1778)
						)
						(arc
							(start 0.2794 0.1778)
							(mid 0.249642 0.249642)
							(end 0.1778 0.2794)
						)
					)
					(width 0)
					(fill yes)
				)
			)
		)
		(pad "2" smd custom
			(at 0 0.4445 90)
			(size 0.1397 0.1397)
			(layers "B.Cu" "B.Mask" "B.Paste")
			(net "GND")
			(options
				(clearance outline)
				(anchor circle)
			)
			(primitives
				(gr_poly
					(pts
						(arc
							(start -0.1778 0.2794)
							(mid -0.249642 0.249642)
							(end -0.2794 0.1778)
						)
						(arc
							(start -0.2794 -0.1778)
							(mid -0.249642 -0.249642)
							(end -0.1778 -0.2794)
						)
						(arc
							(start 0.1778 -0.2794)
							(mid 0.249642 -0.249642)
							(end 0.2794 -0.1778)
						)
						(arc
							(start 0.2794 0.1778)
							(mid 0.249642 0.249642)
							(end 0.1778 0.2794)
						)
					)
					(width 0)
					(fill yes)
				)
			)
		)
	)
	(footprint ""
		(layer "B.Cu")
		(at 63.881 -124.46 90)
		(property "Reference" "R251"
			(at 0 0 90)
			(layer "B.SilkS")
			(hide yes)
			(effects
				(font
					(size 1.27 1.27)
				)
				(justify mirror)
			)
		)
		(property "Value" "0R2J-2-GP"
			(at -0.064008 -3.993896 90)
			(unlocked yes)
			(layer "B.Fab")
			(hide yes)
			(effects
				(font
					(size 1.016 1.016)
					(thickness 0.1524)
				)
				(justify mirror)
			)
		)
		(property "Device Type" "R402H16"
			(at -0.064008 -5.517896 90)
			(unlocked yes)
			(layer "B.Fab")
			(hide yes)
			(effects
				(font
					(size 1.016 1.016)
					(thickness 0.1524)
				)
				(justify mirror)
			)
		)
		(duplicate_pad_numbers_are_jumpers no)
		(fp_line
			(start 0.508 -0.9398)
			(end 0.508 0.9398)
			(stroke
				(width 0.1524)
				(type default)
			)
			(layer "B.SilkS")
		)
		(fp_line
			(start -0.508 -0.9398)
			(end 0.508 -0.9398)
			(stroke
				(width 0.1524)
				(type default)
			)
			(layer "B.SilkS")
		)
		(fp_rect
			(start 0.508 0.9398)
			(end -0.508 -0.9398)
			(stroke
				(width 0)
				(type default)
			)
			(fill no)
			(layer "B.CrtYd")
		)
		(fp_rect
			(start 0.508 0.9398)
			(end -0.508 -0.9398)
			(stroke
				(width 0)
				(type default)
			)
			(fill no)
			(layer "B.Fab")
		)
		(pad "1" smd custom
			(at 0 -0.4445 270)
			(size 0.1397 0.1397)
			(layers "B.Cu" "B.Mask" "B.Paste")
			(net "BMC_I2C6_C_FCB_SDA")
			(options
				(clearance outline)
				(anchor circle)
			)
			(primitives
				(gr_poly
					(pts
						(arc
							(start -0.1778 0.2794)
							(mid -0.249642 0.249642)
							(end -0.2794 0.1778)
						)
						(arc
							(start -0.2794 -0.1778)
							(mid -0.249642 -0.249642)
							(end -0.1778 -0.2794)
						)
						(arc
							(start 0.1778 -0.2794)
							(mid 0.249642 -0.249642)
							(end 0.2794 -0.1778)
						)
						(arc
							(start 0.2794 0.1778)
							(mid 0.249642 0.249642)
							(end 0.1778 0.2794)
						)
					)
					(width 0)
					(fill yes)
				)
			)
		)
		(pad "2" smd custom
			(at 0 0.4445 270)
			(size 0.1397 0.1397)
			(layers "B.Cu" "B.Mask" "B.Paste")
			(net "BMC0_SMB6_DAT")
			(options
				(clearance outline)
				(anchor circle)
			)
			(primitives
				(gr_poly
					(pts
						(arc
							(start -0.1778 0.2794)
							(mid -0.249642 0.249642)
							(end -0.2794 0.1778)
						)
						(arc
							(start -0.2794 -0.1778)
							(mid -0.249642 -0.249642)
							(end -0.1778 -0.2794)
						)
						(arc
							(start 0.1778 -0.2794)
							(mid 0.249642 -0.249642)
							(end 0.2794 -0.1778)
						)
						(arc
							(start 0.2794 0.1778)
							(mid 0.249642 0.249642)
							(end 0.1778 0.2794)
						)
					)
					(width 0)
					(fill yes)
				)
			)
		)
	)
	(footprint ""
		(layer "B.Cu")
		(at 320.167 -68.58 180)
		(property "Reference" "PC96"
			(at 0 0 0)
			(layer "B.SilkS")
			(hide yes)
			(effects
				(font
					(size 1.27 1.27)
				)
				(justify mirror)
			)
		)
		(property "Value" "SC4D7U16V5KX-1-GP"
			(at 0.0762 -6.1214 180)
			(unlocked yes)
			(layer "B.Fab")
			(hide yes)
			(effects
				(font
					(size 1.016 1.016)
					(thickness 0.1524)
				)
				(justify mirror)
			)
		)
		(property "Device Type" "C805H56"
			(at 0.0762 -8.1534 180)
			(unlocked yes)
			(layer "B.Fab")
			(hide yes)
			(effects
				(font
					(size 1.016 1.016)
					(thickness 0.1524)
				)
				(justify mirror)
			)
		)
		(duplicate_pad_numbers_are_jumpers no)
		(fp_line
			(start -0.635 0)
			(end 0.635 0)
			(stroke
				(width 0.508)
				(type default)
			)
			(layer "B.SilkS")
		)
		(fp_rect
			(start 0.9652 1.778)
			(end -0.9652 -1.778)
			(stroke
				(width 0)
				(type default)
			)
			(fill no)
			(layer "B.CrtYd")
		)
		(fp_poly
			(pts
				(xy 0.9652 -1.778) (xy -0.9652 -1.778) (xy -0.9652 1.778) (xy 0.9652 1.778)
			)
			(stroke
				(width 0)
				(type default)
			)
			(fill no)
			(layer "B.Fab")
		)
		(pad "1" smd rect
			(at 0 -0.9652)
			(size 1.397 1.143)
			(layers "B.Cu" "B.Mask" "B.Paste")
			(net "P0V9_E")
		)
		(pad "2" smd rect
			(at 0 0.9652)
			(size 1.397 1.143)
			(layers "B.Cu" "B.Mask" "B.Paste")
			(net "GND")
		)
	)
	(footprint ""
		(layer "B.Cu")
		(at 178.0794 -64.643)
		(property "Reference" "PG27"
			(at 0 0 0)
			(layer "B.SilkS")
			(hide yes)
			(effects
				(font
					(size 1.27 1.27)
				)
				(justify mirror)
			)
		)
		(property "Value" "GAP-CLOSE-PWR-3-GP"
			(at -0.0254 -6.5786 0)
			(unlocked yes)
			(layer "B.Fab")
			(hide yes)
			(effects
				(font
					(size 1.016 1.016)
					(thickness 0.1524)
				)
				(justify mirror)
			)
		)
		(property "Device Type" "GAP-CLOSE-PWR-3"
			(at -0.0254 -8.255 0)
			(unlocked yes)
			(layer "B.Fab")
			(hide yes)
			(effects
				(font
					(size 1.016 1.016)
					(thickness 0.1524)
				)
				(justify mirror)
			)
		)
		(duplicate_pad_numbers_are_jumpers no)
		(fp_rect
			(start 0.7112 0.4572)
			(end -0.7112 -0.4572)
			(stroke
				(width 0)
				(type default)
			)
			(fill no)
			(layer "B.CrtYd")
		)
		(fp_poly
			(pts
				(xy 0.7112 -0.4572) (xy -0.7112 -0.4572) (xy -0.7112 0.4572) (xy 0.7112 0.4572)
			)
			(stroke
				(width 0)
				(type default)
			)
			(fill no)
			(layer "B.Fab")
		)
		(pad "1" smd rect
			(at 0.3048 0 180)
			(size 0.6604 0.762)
			(layers "B.Cu" "B.Mask" "B.Paste")
			(net "DUT_AVD_PCIE")
		)
		(pad "2" smd rect
			(at -0.3048 0 180)
			(size 0.6604 0.762)
			(layers "B.Cu" "B.Mask" "B.Paste")
			(net "P0V9")
		)
	)
	(footprint ""
		(layer "B.Cu")
		(at 10.922 -108.204 90)
		(property "Reference" "PC83"
			(at 0 0 90)
			(layer "B.SilkS")
			(hide yes)
			(effects
				(font
					(size 1.27 1.27)
				)
				(justify mirror)
			)
		)
		(property "Value" "SC1KP50V2KX-1GP"
			(at -1.1811 -2.7051 90)
			(unlocked yes)
			(layer "B.Fab")
			(hide yes)
			(effects
				(font
					(size 1.016 1.016)
					(thickness 0.1524)
				)
				(justify mirror)
			)
		)
		(property "Device Type" "C402H22"
			(at -1.1811 -4.2291 90)
			(unlocked yes)
			(layer "B.Fab")
			(hide yes)
			(effects
				(font
					(size 1.016 1.016)
					(thickness 0.1524)
				)
				(justify mirror)
			)
		)
		(duplicate_pad_numbers_are_jumpers no)
		(fp_rect
			(start 0.4318 0.9525)
			(end -0.4318 -0.9525)
			(stroke
				(width 0)
				(type default)
			)
			(fill no)
			(layer "B.CrtYd")
		)
		(fp_rect
			(start 0.4318 0.9525)
			(end -0.4318 -0.9525)
			(stroke
				(width 0)
				(type default)
			)
			(fill no)
			(layer "B.Fab")
		)
		(pad "1" smd custom
			(at 0 -0.4445 270)
			(size 0.1524 0.1524)
			(layers "B.Cu" "B.Mask" "B.Paste")
			(net "PWRGD_P1V26_STBY")
			(options
				(clearance outline)
				(anchor circle)
			)
			(primitives
				(gr_poly
					(pts
						(arc
							(start 0.3048 0.2032)
							(mid 0.275042 0.275042)
							(end 0.2032 0.3048)
						)
						(arc
							(start -0.2032 0.3048)
							(mid -0.275042 0.275042)
							(end -0.3048 0.2032)
						)
						(arc
							(start -0.3048 -0.2032)
							(mid -0.275042 -0.275042)
							(end -0.2032 -0.3048)
						)
						(arc
							(start 0.2032 -0.3048)
							(mid 0.275042 -0.275042)
							(end 0.3048 -0.2032)
						)
					)
					(width 0)
					(fill yes)
				)
			)
		)
		(pad "2" smd custom
			(at 0 0.4445 270)
			(size 0.1524 0.1524)
			(layers "B.Cu" "B.Mask" "B.Paste")
			(net "GND")
			(options
				(clearance outline)
				(anchor circle)
			)
			(primitives
				(gr_poly
					(pts
						(arc
							(start 0.3048 0.2032)
							(mid 0.275042 0.275042)
							(end 0.2032 0.3048)
						)
						(arc
							(start -0.2032 0.3048)
							(mid -0.275042 0.275042)
							(end -0.3048 0.2032)
						)
						(arc
							(start -0.3048 -0.2032)
							(mid -0.275042 -0.275042)
							(end -0.2032 -0.3048)
						)
						(arc
							(start 0.2032 -0.3048)
							(mid 0.275042 -0.275042)
							(end 0.3048 -0.2032)
						)
					)
					(width 0)
					(fill yes)
				)
			)
		)
	)
)
